(kicad_pcb
	(version 20241229)
	(generator "pcbnew")
	(generator_version "9.0")
	(general
		(thickness 1.711)
		(legacy_teardrops no)
	)
	(paper "A4")
	(title_block
		(title "Antmicro Baseboard for Jetson AGX Thor")
		(date "2026-02-18")
		(rev "1.1.0")
		(company "Antmicro Ltd")
		(comment 1 "www.antmicro.com")
		(comment 9 "footprint 110 of 1170 (J1), pads 404-484 of 699")
	)
	(layers
		(0 "F.Cu" signal)
		(4 "In1.Cu" signal)
		(6 "In2.Cu" signal)
		(8 "In3.Cu" signal)
		(10 "In4.Cu" jumper)
		(12 "In5.Cu" signal)
		(14 "In6.Cu" signal)
		(16 "In7.Cu" signal)
		(18 "In8.Cu" signal)
		(2 "B.Cu" signal)
		(9 "F.Adhes" user "F.Adhesive")
		(11 "B.Adhes" user "B.Adhesive")
		(13 "F.Paste" user)
		(15 "B.Paste" user)
		(5 "F.SilkS" user "F.Silkscreen")
		(7 "B.SilkS" user "B.Silkscreen")
		(1 "F.Mask" user)
		(3 "B.Mask" user)
		(17 "Dwgs.User" user "User.Drawings")
		(19 "Cmts.User" user "User.Comments")
		(21 "Eco1.User" user "User.Eco1")
		(23 "Eco2.User" user "User.Eco2")
		(25 "Edge.Cuts" user)
		(27 "Margin" user)
		(31 "F.CrtYd" user "F.Courtyard")
		(29 "B.CrtYd" user "B.Courtyard")
		(35 "F.Fab" user)
		(33 "B.Fab" user)
	)
	(footprint "antmicro-footprints:Conn_Hermaphroditic_Molex_203456-0003_mirrored"
		(locked yes)
		(layer "F.Cu")
		(at 116.530532 78.15)
		(descr "Mirrored version of: https://www.molex.com/content/dam/molex/molex-dot-com/products/automated/en-us/salesdrawingpdf/203/203456/2034560003_sd.pdf")
		(property "Reference" "J1"
			(at -32.25 -11.2 180)
			(layer "F.SilkS")
			(effects
				(font
					(size 0.7 0.7)
					(thickness 0.15)
				)
				(justify right top)
			)
		)
		(property "Value" "Hermaphroditic_Molex_203456-0003_CUSTOM_Jetson_AGX_Thor_H8mm"
			(at 0.1 12.9 0)
			(layer "F.Fab")
			(effects
				(font
					(size 0.7 0.7)
					(thickness 0.15)
				)
				(justify right top)
			)
		)
		(property "Datasheet" "https://www.molex.com/content/dam/molex/molex-dot-com/products/automated/en-us/salesdrawingpdf/203/203456/2034560003_sd.pdf?inline"
			(at 0.1 0.2 0)
			(layer "F.Fab")
			(hide yes)
			(effects
				(font
					(size 0.7 0.7)
					(thickness 0.15)
				)
				(justify right top)
			)
		)
		(property "Description" "Mirror Mezz Hermaphroditic Connector, 5.50mm Connector Height, BGA-Attach Mounting, 7 Pair, 11 Row, 699 Circuits, 0.76µm Gold Plating, without Pegs"
			(at 0.1 0.2 0)
			(layer "F.Fab")
			(hide yes)
			(effects
				(font
					(size 0.7 0.7)
					(thickness 0.15)
				)
				(justify right top)
			)
		)
		(property "MPN" "203456-0003"
			(at 0 0 0)
			(unlocked yes)
			(layer "F.Fab")
			(hide yes)
			(effects
				(font
					(size 1 1)
					(thickness 0.15)
				)
			)
		)
		(property "Manufacturer" "Molex"
			(at 0 0 0)
			(unlocked yes)
			(layer "F.Fab")
			(hide yes)
			(effects
				(font
					(size 1 1)
					(thickness 0.15)
				)
			)
		)
		(property "Author" "Antmicro"
			(at 0 0 0)
			(unlocked yes)
			(layer "F.Fab")
			(hide yes)
			(effects
				(font
					(size 1 1)
					(thickness 0.15)
				)
			)
		)
		(property "License" "Apache-2.0"
			(at 0 0 0)
			(unlocked yes)
			(layer "F.Fab")
			(hide yes)
			(effects
				(font
					(size 1 1)
					(thickness 0.15)
				)
			)
		)
		(sheetname "/SoM_IO/")
		(sheetfile "som_io.kicad_sch")
		(solder_mask_margin 0.05)
		(attr smd)
		(pad "G22" smd circle
			(at -10.1 -1.5 90)
			(size 0.5 0.5)
			(layers "F.Cu" "F.Mask" "F.Paste")
			(net 662 "/SoM_IO2/USBSS2.TX-")
			(pinfunction "UPHY_TX2_N")
			(pintype "output")
		)
		(pad "G23" smd circle
			(at -9.2 -1.5 90)
			(size 0.5 0.5)
			(layers "F.Cu" "F.Mask" "F.Paste")
			(net 684 "/SoM_IO2/USBSS2.TX+")
			(pinfunction "UPHY_TX2_P")
			(pintype "output")
		)
		(pad "G24" smd circle
			(at -8.3 -1.5 90)
			(size 0.5 0.5)
			(layers "F.Cu" "F.Mask" "F.Paste")
			(net 1 "GND")
			(pinfunction "GND")
			(pintype "passive")
		)
		(pad "G25" smd circle
			(at -7 -1.5 90)
			(size 0.5 0.5)
			(layers "F.Cu" "F.Mask" "F.Paste")
			(net 1 "GND")
			(pinfunction "GND")
			(pintype "passive")
		)
		(pad "G26" smd circle
			(at -6.1 -1.5 90)
			(size 0.5 0.5)
			(layers "F.Cu" "F.Mask" "F.Paste")
			(net 435 "/M.2/PCIe_{C5x4}.TX2-")
			(pinfunction "UPHY_TX10_N")
			(pintype "output")
		)
		(pad "G27" smd circle
			(at -5.2 -1.5 90)
			(size 0.5 0.5)
			(layers "F.Cu" "F.Mask" "F.Paste")
			(net 400 "/M.2/PCIe_{C5x4}.TX2+")
			(pinfunction "UPHY_TX10_P")
			(pintype "output")
		)
		(pad "G28" smd circle
			(at -4.3 -1.5 90)
			(size 0.5 0.5)
			(layers "F.Cu" "F.Mask" "F.Paste")
			(net 1 "GND")
			(pinfunction "GND")
			(pintype "passive")
		)
		(pad "G29" smd circle
			(at -3 -1.5 90)
			(size 0.5 0.5)
			(layers "F.Cu" "F.Mask" "F.Paste")
			(net 1 "GND")
			(pinfunction "GND")
			(pintype "passive")
		)
		(pad "G30" smd circle
			(at -2.1 -1.5 90)
			(size 0.5 0.5)
			(layers "F.Cu" "F.Mask" "F.Paste")
			(net 604 "unconnected-(J1B-UPHY_TX14_N-PadG30)")
			(pinfunction "UPHY_TX14_N")
			(pintype "output+no_connect")
		)
		(pad "G31" smd circle
			(at -1.2 -1.5 90)
			(size 0.5 0.5)
			(layers "F.Cu" "F.Mask" "F.Paste")
			(net 693 "unconnected-(J1B-UPHY_TX14_P-PadG31)")
			(pinfunction "UPHY_TX14_P")
			(pintype "output+no_connect")
		)
		(pad "G32" smd circle
			(at -0.3 -1.5 90)
			(size 0.5 0.5)
			(layers "F.Cu" "F.Mask" "F.Paste")
			(net 1 "GND")
			(pinfunction "GND")
			(pintype "passive")
		)
		(pad "G33" smd circle
			(at 1 -1.5 90)
			(size 0.5 0.5)
			(layers "F.Cu" "F.Mask" "F.Paste")
			(net 1 "GND")
			(pinfunction "GND")
			(pintype "passive")
		)
		(pad "G34" smd circle
			(at 1.9 -1.5 90)
			(size 0.5 0.5)
			(layers "F.Cu" "F.Mask" "F.Paste")
			(net 16 "/M.2/PCIe_{C1x1}.TX0-")
			(pinfunction "UPHY_TX3_N")
			(pintype "output")
		)
		(pad "G35" smd circle
			(at 2.8 -1.5 90)
			(size 0.5 0.5)
			(layers "F.Cu" "F.Mask" "F.Paste")
			(net 15 "/M.2/PCIe_{C1x1}.TX0+")
			(pinfunction "UPHY_TX3_P")
			(pintype "output")
		)
		(pad "G36" smd circle
			(at 3.7 -1.5 90)
			(size 0.5 0.5)
			(layers "F.Cu" "F.Mask" "F.Paste")
			(net 1 "GND")
			(pinfunction "GND")
			(pintype "passive")
		)
		(pad "G37" smd circle
			(at 5 -1.5 90)
			(size 0.5 0.5)
			(layers "F.Cu" "F.Mask" "F.Paste")
			(net 1 "GND")
			(pinfunction "GND")
			(pintype "passive")
		)
		(pad "G38" smd circle
			(at 5.9 -1.5 90)
			(size 0.5 0.5)
			(layers "F.Cu" "F.Mask" "F.Paste")
			(net 142 "/Expansion connector/CAN0.DOUT")
			(pinfunction "CAN0_DOUT")
			(pintype "output")
		)
		(pad "G39" smd circle
			(at 6.8 -1.5 90)
			(size 0.5 0.5)
			(layers "F.Cu" "F.Mask" "F.Paste")
			(net 105 "/Expansion connector/CAN0.DIN")
			(pinfunction "CAN0_DIN")
			(pintype "input")
		)
		(pad "G40" smd circle
			(at 7.7 -1.5 90)
			(size 0.5 0.5)
			(layers "F.Cu" "F.Mask" "F.Paste")
			(net 1 "GND")
			(pinfunction "GND")
			(pintype "passive")
		)
		(pad "G41" smd circle
			(at 8.6 -1.5 90)
			(size 0.5 0.5)
			(layers "F.Cu" "F.Mask" "F.Paste")
			(net 77 "/CSI/CAM1.CSI1_D0+")
			(pinfunction "CSI1_D0_P")
			(pintype "input")
		)
		(pad "G42" smd circle
			(at 9.5 -1.5 90)
			(size 0.5 0.5)
			(layers "F.Cu" "F.Mask" "F.Paste")
			(net 134 "/CSI/CAM1.CSI1_D0-")
			(pinfunction "CSI1_D0_N")
			(pintype "input")
		)
		(pad "G43" smd circle
			(at 10.4 -1.5 90)
			(size 0.5 0.5)
			(layers "F.Cu" "F.Mask" "F.Paste")
			(net 1 "GND")
			(pinfunction "GND")
			(pintype "passive")
		)
		(pad "G44" smd circle
			(at 11.3 -1.5 90)
			(size 0.5 0.5)
			(layers "F.Cu" "F.Mask" "F.Paste")
			(net 161 "/CSI/CAM0.CSI3_D1+")
			(pinfunction "CSI3_D1_P")
			(pintype "input")
		)
		(pad "G45" smd circle
			(at 12.2 -1.5 90)
			(size 0.5 0.5)
			(layers "F.Cu" "F.Mask" "F.Paste")
			(net 154 "/CSI/CAM0.CSI3_D1-")
			(pinfunction "CSI3_D1_N")
			(pintype "input")
		)
		(pad "G46" smd circle
			(at 13.1 -1.5 90)
			(size 0.5 0.5)
			(layers "F.Cu" "F.Mask" "F.Paste")
			(net 1 "GND")
			(pinfunction "GND")
			(pintype "passive")
		)
		(pad "G47" smd circle
			(at 14 -1.5 90)
			(size 0.5 0.5)
			(layers "F.Cu" "F.Mask" "F.Paste")
			(net 122 "/CSI/CAM2.CSI4_D0-")
			(pinfunction "CSI4_D0_N")
			(pintype "input")
		)
		(pad "G48" smd circle
			(at 14.9 -1.5 90)
			(size 0.5 0.5)
			(layers "F.Cu" "F.Mask" "F.Paste")
			(net 144 "/CSI/CAM2.CSI4_D0+")
			(pinfunction "CSI4_D0_P")
			(pintype "input")
		)
		(pad "G49" smd circle
			(at 15.8 -1.5 90)
			(size 0.5 0.5)
			(layers "F.Cu" "F.Mask" "F.Paste")
			(net 1 "GND")
			(pinfunction "GND")
			(pintype "passive")
		)
		(pad "G50" smd circle
			(at 16.7 -1.5 90)
			(size 0.5 0.5)
			(layers "F.Cu" "F.Mask" "F.Paste")
			(net 1249 "/SoM_IO2/DP1.TX1_C-")
			(pinfunction "DP1_D1_HDMI_D1_N")
			(pintype "output")
		)
		(pad "G51" smd circle
			(at 17.6 -1.5 90)
			(size 0.5 0.5)
			(layers "F.Cu" "F.Mask" "F.Paste")
			(net 1209 "/SoM_IO2/DP1.TX1_C+")
			(pinfunction "DP1_D1_HDMI_D1_P")
			(pintype "output")
		)
		(pad "G52" smd circle
			(at 18.5 -1.5 90)
			(size 0.5 0.5)
			(layers "F.Cu" "F.Mask" "F.Paste")
			(net 1 "GND")
			(pinfunction "GND")
			(pintype "passive")
		)
		(pad "G53" smd circle
			(at 19.4 -1.5 90)
			(size 0.5 0.5)
			(layers "F.Cu" "F.Mask" "F.Paste")
			(net 1088 "/SoM_IO2/DP0.AUX_C+")
			(pinfunction "DP_AUX_CH0_P")
			(pintype "bidirectional")
		)
		(pad "G54" smd circle
			(at 20.3 -1.5 90)
			(size 0.5 0.5)
			(layers "F.Cu" "F.Mask" "F.Paste")
			(net 1112 "/SoM_IO2/DP0.AUX_C-")
			(pinfunction "DP_AUX_CH0_N")
			(pintype "bidirectional")
		)
		(pad "G55" smd circle
			(at 21.2 -1.5 90)
			(size 0.5 0.5)
			(layers "F.Cu" "F.Mask" "F.Paste")
			(net 747 "unconnected-(J1C-GPIO23-PadG55)")
			(pinfunction "GPIO23")
			(pintype "passive+no_connect")
		)
		(pad "G56" smd circle
			(at 22.1 -1.5 90)
			(size 0.5 0.5)
			(layers "F.Cu" "F.Mask" "F.Paste")
			(net 49 "/Expansion connector/SPI3.MOSI")
			(pinfunction "SPI3_MOSI")
			(pintype "bidirectional")
		)
		(pad "G57" smd circle
			(at 23 -1.5 90)
			(size 0.5 0.5)
			(layers "F.Cu" "F.Mask" "F.Paste")
			(net 1 "GND")
			(pinfunction "GND")
			(pintype "passive")
		)
		(pad "G58" smd circle
			(at 23.9 -1.5 90)
			(size 0.5 0.5)
			(layers "F.Cu" "F.Mask" "F.Paste")
			(net 82 "/Expansion connector/UART2.RTS")
			(pinfunction "UART2_RTS")
			(pintype "output")
		)
		(pad "G59" smd circle
			(at 24.8 -1.5 90)
			(size 0.5 0.5)
			(layers "F.Cu" "F.Mask" "F.Paste")
			(net 673 "Net-(J1A-THERM_SHDN_REQ_N)")
			(pinfunction "THERM_SHDN_REQ_N")
			(pintype "output")
		)
		(pad "G60" smd circle
			(at 25.7 -1.5 90)
			(size 0.5 0.5)
			(layers "F.Cu" "F.Mask" "F.Paste")
			(net 652 "/SoM_IO2/NVDBG_SEL")
			(pinfunction "NVDBG_SEL")
			(pintype "passive")
		)
		(pad "G61" smd circle
			(at 26.6 -1.5 90)
			(size 0.5 0.5)
			(layers "F.Cu" "F.Mask" "F.Paste")
			(net 627 "/SoM_IO2/JTAG_TRST_N")
			(pinfunction "JTAG_TRST_N")
			(pintype "passive")
		)
		(pad "G62" smd circle
			(at 27.5 -1.5 90)
			(size 0.5 0.5)
			(layers "F.Cu" "F.Mask" "F.Paste")
			(net 1 "GND")
			(pinfunction "GND")
			(pintype "passive")
		)
		(pad "G63" smd circle
			(at 28.4 -1.5 90)
			(size 0.5 0.5)
			(layers "F.Cu" "F.Mask" "F.Paste")
			(net 12 "SYS_VIN_HV")
			(pinfunction "SYS_VIN_HV")
			(pintype "passive")
		)
		(pad "G64" smd circle
			(at 29.3 -1.5 90)
			(size 0.5 0.5)
			(layers "F.Cu" "F.Mask" "F.Paste")
			(net 12 "SYS_VIN_HV")
			(pinfunction "SYS_VIN_HV")
			(pintype "passive")
		)
		(pad "G65" smd circle
			(at 30.2 -1.5 90)
			(size 0.5 0.5)
			(layers "F.Cu" "F.Mask" "F.Paste")
			(net 12 "SYS_VIN_HV")
			(pinfunction "SYS_VIN_HV")
			(pintype "passive")
		)
		(pad "H1" smd circle
			(at -30 -3 90)
			(size 0.5 0.5)
			(layers "F.Cu" "F.Mask" "F.Paste")
			(net 12 "SYS_VIN_HV")
			(pinfunction "SYS_VIN_HV")
			(pintype "passive")
		)
		(pad "H2" smd circle
			(at -29.1 -3 90)
			(size 0.5 0.5)
			(layers "F.Cu" "F.Mask" "F.Paste")
			(net 12 "SYS_VIN_HV")
			(pinfunction "SYS_VIN_HV")
			(pintype "passive")
		)
		(pad "H3" smd circle
			(at -28.2 -3 90)
			(size 0.5 0.5)
			(layers "F.Cu" "F.Mask" "F.Paste")
			(net 12 "SYS_VIN_HV")
			(pinfunction "SYS_VIN_HV")
			(pintype "passive")
		)
		(pad "H4" smd circle
			(at -27.3 -3 90)
			(size 0.5 0.5)
			(layers "F.Cu" "F.Mask" "F.Paste")
			(net 1 "GND")
			(pinfunction "GND")
			(pintype "passive")
		)
		(pad "H5" smd circle
			(at -26.4 -3 90)
			(size 0.5 0.5)
			(layers "F.Cu" "F.Mask" "F.Paste")
			(net 464 "/Expansion connector/GPIO.20")
			(pinfunction "GPIO59")
			(pintype "passive")
		)
		(pad "H6" smd circle
			(at -25.5 -3 90)
			(size 0.5 0.5)
			(layers "F.Cu" "F.Mask" "F.Paste")
			(net 687 "unconnected-(J1I-UART4_RX-PadH6)")
			(pinfunction "UART4_RX")
			(pintype "input+no_connect")
		)
		(pad "H7" smd circle
			(at -24.6 -3 90)
			(size 0.5 0.5)
			(layers "F.Cu" "F.Mask" "F.Paste")
			(net 1 "GND")
			(pinfunction "GND")
			(pintype "passive")
		)
		(pad "H8" smd circle
			(at -23.7 -3 90)
			(size 0.5 0.5)
			(layers "F.Cu" "F.Mask" "F.Paste")
			(net 76 "/SoM_IO/I2S_{M.2}.SDIN")
			(pinfunction "I2S1_SDIN")
			(pintype "input")
		)
		(pad "H9" smd circle
			(at -22.8 -3 90)
			(size 0.5 0.5)
			(layers "F.Cu" "F.Mask" "F.Paste")
			(net 362 "/Expansion connector/GPIO.MCLK01")
			(pinfunction "MCLK01")
			(pintype "output")
		)
		(pad "H10" smd circle
			(at -21.9 -3 90)
			(size 0.5 0.5)
			(layers "F.Cu" "F.Mask" "F.Paste")
			(net 714 "unconnected-(J1C-PEX_C4_RST_N-PadH10)")
			(pinfunction "PEX_C4_RST_N")
			(pintype "output+no_connect")
		)
		(pad "H11" smd circle
			(at -21 -3 90)
			(size 0.5 0.5)
			(layers "F.Cu" "F.Mask" "F.Paste")
			(net 1 "GND")
			(pinfunction "GND")
			(pintype "passive")
		)
		(pad "H12" smd circle
			(at -20.1 -3 90)
			(size 0.5 0.5)
			(layers "F.Cu" "F.Mask" "F.Paste")
			(net 467 "/Expansion connector/PCIe_{C3x2}.TX1+")
			(pinfunction "UPHY_TX7_P")
			(pintype "output")
		)
		(pad "H13" smd circle
			(at -19.2 -3 90)
			(size 0.5 0.5)
			(layers "F.Cu" "F.Mask" "F.Paste")
			(net 519 "/Expansion connector/PCIe_{C3x2}.TX1-")
			(pinfunction "UPHY_TX7_N")
			(pintype "output")
		)
		(pad "H14" smd circle
			(at -18.3 -3 90)
			(size 0.5 0.5)
			(layers "F.Cu" "F.Mask" "F.Paste")
			(net 1 "GND")
			(pinfunction "GND")
			(pintype "passive")
		)
		(pad "H15" smd circle
			(at -17 -3 90)
			(size 0.5 0.5)
			(layers "F.Cu" "F.Mask" "F.Paste")
			(net 1 "GND")
			(pinfunction "GND")
			(pintype "passive")
		)
		(pad "H16" smd circle
			(at -16.1 -3 90)
			(size 0.5 0.5)
			(layers "F.Cu" "F.Mask" "F.Paste")
			(net 165 "/Expansion connector/I2S3.CLK")
			(pinfunction "GPIO61")
			(pintype "passive")
		)
		(pad "H17" smd circle
			(at -15.2 -3 90)
			(size 0.5 0.5)
			(layers "F.Cu" "F.Mask" "F.Paste")
			(net 141 "/Expansion connector/I2S3.SDOUT")
			(pinfunction "GPIO62")
			(pintype "passive")
		)
		(pad "H18" smd circle
			(at -14.3 -3 90)
			(size 0.5 0.5)
			(layers "F.Cu" "F.Mask" "F.Paste")
			(net 1 "GND")
			(pinfunction "GND")
			(pintype "passive")
		)
		(pad "H19" smd circle
			(at -13 -3 90)
			(size 0.5 0.5)
			(layers "F.Cu" "F.Mask" "F.Paste")
			(net 1 "GND")
			(pinfunction "GND")
			(pintype "passive")
		)
		(pad "H20" smd circle
			(at -12.1 -3 90)
			(size 0.5 0.5)
			(layers "F.Cu" "F.Mask" "F.Paste")
			(net 768 "unconnected-(J1B-UPHY_TX5_P-PadH20)")
			(pinfunction "UPHY_TX5_P")
			(pintype "output+no_connect")
		)
		(pad "H21" smd circle
			(at -11.2 -3 90)
			(size 0.5 0.5)
			(layers "F.Cu" "F.Mask" "F.Paste")
			(net 672 "unconnected-(J1B-UPHY_TX5_N-PadH21)")
			(pinfunction "UPHY_TX5_N")
			(pintype "output+no_connect")
		)
		(pad "H22" smd circle
			(at -10.3 -3 90)
			(size 0.5 0.5)
			(layers "F.Cu" "F.Mask" "F.Paste")
			(net 1 "GND")
			(pinfunction "GND")
			(pintype "passive")
		)
		(pad "H23" smd circle
			(at -9 -3 90)
			(size 0.5 0.5)
			(layers "F.Cu" "F.Mask" "F.Paste")
			(net 1 "GND")
			(pinfunction "GND")
			(pintype "passive")
		)
		(pad "H24" smd circle
			(at -8.1 -3 90)
			(size 0.5 0.5)
			(layers "F.Cu" "F.Mask" "F.Paste")
			(net 382 "/M.2/PCIe_{C5x4}.TX0+")
			(pinfunction "UPHY_TX8_P")
			(pintype "output")
		)
		(pad "H25" smd circle
			(at -7.2 -3 90)
			(size 0.5 0.5)
			(layers "F.Cu" "F.Mask" "F.Paste")
			(net 411 "/M.2/PCIe_{C5x4}.TX0-")
			(pinfunction "UPHY_TX8_N")
			(pintype "output")
		)
		(pad "H26" smd circle
			(at -6.3 -3 90)
			(size 0.5 0.5)
			(layers "F.Cu" "F.Mask" "F.Paste")
			(net 1 "GND")
			(pinfunction "GND")
			(pintype "passive")
		)
		(pad "H27" smd circle
			(at -5 -3 90)
			(size 0.5 0.5)
			(layers "F.Cu" "F.Mask" "F.Paste")
			(net 1 "GND")
			(pinfunction "GND")
			(pintype "passive")
		)
		(pad "H28" smd circle
			(at -4.1 -3 90)
			(size 0.5 0.5)
			(layers "F.Cu" "F.Mask" "F.Paste")
			(net 106 "/SFP/SFI.TX+")
			(pinfunction "UPHY_TX12_P")
			(pintype "output")
		)
		(pad "H29" smd circle
			(at -3.2 -3 90)
			(size 0.5 0.5)
			(layers "F.Cu" "F.Mask" "F.Paste")
			(net 132 "/SFP/SFI.TX-")
			(pinfunction "UPHY_TX12_N")
			(pintype "output")
		)
		(pad "H30" smd circle
			(at -2.3 -3 90)
			(size 0.5 0.5)
			(layers "F.Cu" "F.Mask" "F.Paste")
			(net 1 "GND")
			(pinfunction "GND")
			(pintype "passive")
		)
		(pad "H31" smd circle
			(at -1 -3 90)
			(size 0.5 0.5)
			(layers "F.Cu" "F.Mask" "F.Paste")
			(net 1 "GND")
			(pinfunction "GND")
			(pintype "passive")
		)
		(pad "H32" smd circle
			(at -0.1 -3 90)
			(size 0.5 0.5)
			(layers "F.Cu" "F.Mask" "F.Paste")
			(net 1267 "/SoM_IO2/DP3.TX3_C+")
			(pinfunction "DP3_D3_HDMI_CK_P")
			(pintype "output")
		)
		(pad "H33" smd circle
			(at 0.8 -3 90)
			(size 0.5 0.5)
			(layers "F.Cu" "F.Mask" "F.Paste")
			(net 1271 "/SoM_IO2/DP3.TX3_C-")
			(pinfunction "DP3_D3_HDMI_CK_N")
			(pintype "output")
		)
		(pad "H34" smd circle
			(at 1.7 -3 90)
			(size 0.5 0.5)
			(layers "F.Cu" "F.Mask" "F.Paste")
			(net 1 "GND")
			(pinfunction "GND")
			(pintype "passive")
		)
		(pad "H35" smd circle
			(at 3 -3 90)
			(size 0.5 0.5)
			(layers "F.Cu" "F.Mask" "F.Paste")
			(net 1 "GND")
			(pinfunction "GND")
			(pintype "passive")
		)
		(pad "H36" smd circle
			(at 3.9 -3 90)
			(size 0.5 0.5)
			(layers "F.Cu" "F.Mask" "F.Paste")
			(net 50 "/Expansion connector/CAN1.DIN")
			(pinfunction "CAN1_DIN")
			(pintype "input")
		)
		(pad "H37" smd circle
			(at 4.8 -3 90)
			(size 0.5 0.5)
			(layers "F.Cu" "F.Mask" "F.Paste")
			(net 81 "/Expansion connector/CAN1.DOUT")
			(pinfunction "CAN1_DOUT")
			(pintype "output")
		)
	)
)
